(kicad_pcb
	(version 20260206)
	(generator "pcbnew")
	(generator_version "10.0")
	(general
		(thickness 1.6)
		(legacy_teardrops no)
	)
	(paper "A4")
	(title_block
		(title "04192023_DAF0TMB3IC0_F0TG_MB_C_brd_V02_OCP.brd")
		(comment 1 "Grand Teton / footprints 2134-2139 of 8354")
	)
	(layers
		(0 "F.Cu" signal "TOP")
		(4 "In1.Cu" signal "GND")
		(6 "In2.Cu" signal "IN1")
		(8 "In3.Cu" signal "GND1")
		(10 "In4.Cu" signal "IN2")
		(12 "In5.Cu" signal "GND2")
		(14 "In6.Cu" signal "IN3")
		(16 "In7.Cu" signal "GND3")
		(18 "In8.Cu" signal "VCC")
		(20 "In9.Cu" signal "VCC1")
		(22 "In10.Cu" signal "GND4")
		(24 "In11.Cu" signal "IN4")
		(26 "In12.Cu" signal "GND5")
		(28 "In13.Cu" signal "IN5")
		(30 "In14.Cu" signal "GND6")
		(32 "In15.Cu" signal "IN6")
		(34 "In16.Cu" signal "GND7")
		(2 "B.Cu" signal "BOTTOM")
		(9 "F.Adhes" user "F.Adhesive")
		(11 "B.Adhes" user "B.Adhesive")
		(13 "F.Paste" user "Package Geometry/Pastemask Top")
		(15 "B.Paste" user "Package Geometry/Pastemask Bottom")
		(5 "F.SilkS" user "Ref Des/Silkscreen Top")
		(7 "B.SilkS" user "Ref Des/Silkscreen Bottom")
		(1 "F.Mask" user "Board Geometry/Soldermask Top")
		(3 "B.Mask" user "Board Geometry/Soldermask Bottom")
		(17 "Dwgs.User" user "User.Drawings")
		(19 "Cmts.User" user "User.Comments")
		(21 "Eco1.User" user "User.Eco1")
		(23 "Eco2.User" user "User.Eco2")
		(25 "Edge.Cuts" user "Board Geometry/Outline")
		(27 "Margin" user)
		(31 "F.CrtYd" user "Package Geometry/Place Bound Top")
		(29 "B.CrtYd" user "Package Geometry/Place Bound Bottom")
		(35 "F.Fab" user "Ref Des/Assembly Top")
		(33 "B.Fab" user "Ref Des/Assembly Bottom")
	)
	(footprint ""
		(layer "F.Cu")
		(at 356.033578 -169.495978 180)
		(property "Reference" "PU48"
			(at 0.486156 -7.523226 0)
			(unlocked yes)
			(layer "F.SilkS")
			(effects
				(font
					(size 0.7874 0.5842)
					(thickness 0.1524)
				)
				(justify left)
			)
		)
		(property "Value" ""
			(at 0 0 180)
			(layer "F.Fab")
			(effects
				(font
					(size 1.27 1.27)
				)
			)
		)
		(duplicate_pad_numbers_are_jumpers no)
		(fp_line
			(start 2.500122 2.999994)
			(end 2.2987 2.999994)
			(stroke
				(width 0.1524)
				(type default)
			)
			(layer "F.SilkS")
		)
		(fp_line
			(start 2.500122 2.339594)
			(end 2.500122 2.999994)
			(stroke
				(width 0.1524)
				(type default)
			)
			(layer "F.SilkS")
		)
		(fp_line
			(start 2.500122 -2.999994)
			(end 2.500122 -2.44348)
			(stroke
				(width 0.1524)
				(type default)
			)
			(layer "F.SilkS")
		)
		(fp_line
			(start 2.31394 -2.999994)
			(end 2.500122 -2.999994)
			(stroke
				(width 0.1524)
				(type default)
			)
			(layer "F.SilkS")
		)
		(fp_line
			(start -2.2987 2.999994)
			(end -2.500122 2.999994)
			(stroke
				(width 0.1524)
				(type default)
			)
			(layer "F.SilkS")
		)
		(fp_line
			(start -2.500122 2.999994)
			(end -2.500122 2.339594)
			(stroke
				(width 0.1524)
				(type default)
			)
			(layer "F.SilkS")
		)
		(fp_line
			(start -2.500122 0.6604)
			(end -2.500122 0.229108)
			(stroke
				(width 0.1524)
				(type default)
			)
			(layer "F.SilkS")
		)
		(fp_line
			(start -2.500122 -2.529078)
			(end -2.500122 -2.999994)
			(stroke
				(width 0.1524)
				(type default)
			)
			(layer "F.SilkS")
		)
		(fp_line
			(start -2.500122 -2.999994)
			(end -2.24409 -2.999994)
			(stroke
				(width 0.1524)
				(type default)
			)
			(layer "F.SilkS")
		)
		(fp_poly
			(pts
				(xy -2.712466 -2.468372) (xy -3.43662 -2.709672) (xy -2.95402 -3.192526)
			)
			(stroke
				(width 0)
				(type default)
			)
			(fill yes)
			(layer "F.SilkS")
		)
		(fp_line
			(start 2.500122 2.999994)
			(end -2.500122 2.999994)
			(stroke
				(width 0.1)
				(type default)
			)
			(layer "F.Fab")
		)
		(fp_line
			(start 2.500122 -2.999994)
			(end 2.500122 2.999994)
			(stroke
				(width 0.1)
				(type default)
			)
			(layer "F.Fab")
		)
		(fp_line
			(start -2.500122 2.999994)
			(end -2.500122 -2.999994)
			(stroke
				(width 0.1)
				(type default)
			)
			(layer "F.Fab")
		)
		(fp_line
			(start -2.500122 -2.999994)
			(end 2.500122 -2.999994)
			(stroke
				(width 0.1)
				(type default)
			)
			(layer "F.Fab")
		)
		(fp_poly
			(pts
				(xy -4.218432 -2.783078) (xy -4.218432 -1.767078) (xy -3.202432 -2.275078)
			)
			(stroke
				(width 0)
				(type default)
			)
			(fill yes)
			(layer "F.Fab")
		)
		(pad "1" smd rect
			(at -2.400046 -2.275078 270)
			(size 0.2286 0.6096)
			(layers "F.Cu" "F.Mask" "F.Paste")
			(net "PVDDCR_CPU0_P0_VOS5")
		)
		(pad "2" smd rect
			(at -2.400046 -1.82499 270)
			(size 0.2286 0.6096)
			(layers "F.Cu" "F.Mask" "F.Paste")
			(net "GND")
		)
		(pad "3" smd rect
			(at -2.400046 -1.374902 270)
			(size 0.2286 0.6096)
			(layers "F.Cu" "F.Mask" "F.Paste")
			(net "PVDDCR_CPU0_P0_VCC5")
		)
		(pad "4" smd rect
			(at -2.400046 -0.925068 270)
			(size 0.2286 0.6096)
			(layers "F.Cu" "F.Mask" "F.Paste")
			(net "PVDDCR_CPU0_P0_PVCC")
		)
		(pad "5" smd rect
			(at -2.400046 -0.47498 270)
			(size 0.2286 0.6096)
			(layers "F.Cu" "F.Mask" "F.Paste")
			(net "GND")
		)
		(pad "6" smd rect
			(at -2.400046 -0.024892 270)
			(size 0.2286 0.6096)
			(layers "F.Cu" "F.Mask" "F.Paste")
			(net "NC_PVDDCR_CPU0_P0_GL1_5")
		)
		(pad "7_9-20_24" smd circle
			(at 0 1.150112 270)
			(size 0 0)
			(layers "F.Cu" "F.Mask" "F.Paste")
			(net "GND")
		)
		(pad "10_19" smd rect
			(at 0 2.899918 270)
			(size 0.6096 4.318)
			(layers "F.Cu" "F.Mask" "F.Paste")
			(net "SW_PVDDCR_CPU0_P0_SW5")
		)
		(pad "25_29" smd rect
			(at 1.549908 -1.279906 90)
			(size 2.0574 2.3114)
			(layers "F.Cu" "F.Mask" "F.Paste")
			(net "SW_P12V_AUX_PVDDCR_CPU0_P0_FLT")
		)
		(pad "30" smd rect
			(at 2.05994 -2.899918 180)
			(size 0.2286 0.6096)
			(layers "F.Cu" "F.Mask" "F.Paste")
			(net "SW_P12V_AUX_PVDDCR_CPU0_P0_FLT")
		)
		(pad "31" smd rect
			(at 1.610106 -2.899918 180)
			(size 0.2286 0.6096)
			(layers "F.Cu" "F.Mask" "F.Paste")
			(net "NC_PVDDCR_CPU0_P0_DNC5")
		)
		(pad "32" smd rect
			(at 1.160018 -2.899918 180)
			(size 0.2286 0.6096)
			(layers "F.Cu" "F.Mask" "F.Paste")
			(net "SW_PVDDCR_CPU0_P0_PH5")
		)
		(pad "33" smd rect
			(at 0.70993 -2.899918 180)
			(size 0.2286 0.6096)
			(layers "F.Cu" "F.Mask" "F.Paste")
			(net "SW_PVDDCR_CPU0_P0_BOOT5")
		)
		(pad "34" smd rect
			(at 0.260096 -2.899918 180)
			(size 0.2286 0.6096)
			(layers "F.Cu" "F.Mask" "F.Paste")
			(net "PVDDCR_CPU0_P0_PWM5")
		)
		(pad "35" smd rect
			(at -0.189992 -2.899918 180)
			(size 0.2286 0.6096)
			(layers "F.Cu" "F.Mask" "F.Paste")
			(net "PVDDCR_CPU0_P0_VCC5")
		)
		(pad "36" smd rect
			(at -0.64008 -2.899918 180)
			(size 0.2286 0.6096)
			(layers "F.Cu" "F.Mask" "F.Paste")
			(net "PVDDCR_CPU0_P0_TEMP0")
		)
		(pad "37" smd rect
			(at -1.089914 -2.899918 180)
			(size 0.2286 0.6096)
			(layers "F.Cu" "F.Mask" "F.Paste")
			(net "PVDDCR_CPU0_P0_LSET5")
		)
		(pad "38" smd rect
			(at -1.540002 -2.899918 180)
			(size 0.2286 0.6096)
			(layers "F.Cu" "F.Mask" "F.Paste")
			(net "PVDDCR_CPU0_P0_IMON5")
		)
		(pad "39" smd rect
			(at -1.99009 -2.899918 180)
			(size 0.2286 0.6096)
			(layers "F.Cu" "F.Mask" "F.Paste")
			(net "PVDDCR_CPU0_P0_VCCS")
		)
		(pad "40" smd rect
			(at -0.87503 -1.27508 180)
			(size 1.7526 1.9558)
			(layers "F.Cu" "F.Mask" "F.Paste")
			(net "GND")
		)
		(pad "41" smd rect
			(at -1.525016 0.249936 90)
			(size 0.3048 0.4572)
			(layers "F.Cu" "F.Mask" "F.Paste")
			(net "NC_PVDDCR_CPU0_P0_GL2_5")
		)
		(zone
			(layer "F.Cu")
			(hatch none 0.5)
			(connect_pads
				(clearance 0)
			)
			(min_thickness 0.25)
			(keepout
				(tracks not_allowed)
				(vias allowed)
				(pads allowed)
				(copperpour not_allowed)
				(footprints allowed)
			)
			(placement
				(enabled no)
				(sheetname "")
			)
			(fill
				(thermal_gap 0.5)
				(thermal_bridge_width 0.5)
				(island_removal_mode 0)
			)
			(polygon
				(pts
					(xy 358.5337 -172.070776) (xy 358.5337 -171.746672) (xy 353.533456 -171.746672) (xy 353.533456 -172.076618)
					(xy 353.823778 -172.076618) (xy 353.823778 -172.040296) (xy 358.243378 -172.040296) (xy 358.243378 -172.070776)
				)
			)
		)
		(zone
			(layer "F.Cu")
			(hatch none 0.5)
			(connect_pads
				(clearance 0)
			)
			(min_thickness 0.25)
			(keepout
				(tracks not_allowed)
				(vias allowed)
				(pads allowed)
				(copperpour not_allowed)
				(footprints allowed)
			)
			(placement
				(enabled no)
				(sheetname "")
			)
			(fill
				(thermal_gap 0.5)
				(thermal_bridge_width 0.5)
				(island_removal_mode 0)
			)
			(polygon
				(pts
					(xy 355.981508 -169.249598) (xy 355.981508 -167.192198) (xy 357.835708 -167.192198) (xy 357.835708 -167.433244)
					(xy 358.078024 -167.433244) (xy 358.078024 -166.95166) (xy 354.210112 -166.95166) (xy 354.210112 -167.136572)
					(xy 355.69017 -167.136572) (xy 355.69017 -169.295572) (xy 353.533456 -169.295572) (xy 353.533456 -169.545254)
					(xy 355.698806 -169.545254) (xy 355.981508 -169.262552)
				)
			)
		)
	)
	(footprint ""
		(layer "F.Cu")
		(at 148.641562 -43.03141)
		(property "Reference" "R1703"
			(at 0 0 0)
			(layer "F.SilkS")
			(hide yes)
			(effects
				(font
					(size 1.27 1.27)
				)
			)
		)
		(property "Value" ""
			(at 0 0 0)
			(layer "F.Fab")
			(effects
				(font
					(size 1.27 1.27)
				)
			)
		)
		(duplicate_pad_numbers_are_jumpers no)
		(fp_line
			(start -0.7874 -0.4064)
			(end 0.7874 -0.4064)
			(stroke
				(width 0.1524)
				(type default)
			)
			(layer "F.SilkS")
		)
		(fp_line
			(start -0.7874 0.4064)
			(end -0.7874 -0.4064)
			(stroke
				(width 0.1524)
				(type default)
			)
			(layer "F.SilkS")
		)
		(fp_line
			(start 0.7874 -0.4064)
			(end 0.7874 0.4064)
			(stroke
				(width 0.1524)
				(type default)
			)
			(layer "F.SilkS")
		)
		(fp_line
			(start 0.7874 0.4064)
			(end -0.7874 0.4064)
			(stroke
				(width 0.1524)
				(type default)
			)
			(layer "F.SilkS")
		)
		(fp_line
			(start -0.67945 -0.305054)
			(end -0.12065 -0.305054)
			(stroke
				(width 0.1)
				(type default)
			)
			(layer "F.Fab")
		)
		(fp_line
			(start -0.67945 0.3048)
			(end -0.67945 -0.305054)
			(stroke
				(width 0.1)
				(type default)
			)
			(layer "F.Fab")
		)
		(fp_line
			(start -0.12065 -0.305054)
			(end -0.12065 -0.2794)
			(stroke
				(width 0.1)
				(type default)
			)
			(layer "F.Fab")
		)
		(fp_line
			(start -0.12065 -0.2794)
			(end 0.12065 -0.2794)
			(stroke
				(width 0.1)
				(type default)
			)
			(layer "F.Fab")
		)
		(fp_line
			(start -0.12065 0.2794)
			(end -0.12065 0.3048)
			(stroke
				(width 0.1)
				(type default)
			)
			(layer "F.Fab")
		)
		(fp_line
			(start -0.12065 0.3048)
			(end -0.67945 0.3048)
			(stroke
				(width 0.1)
				(type default)
			)
			(layer "F.Fab")
		)
		(fp_line
			(start 0.120396 0.2794)
			(end -0.12065 0.2794)
			(stroke
				(width 0.1)
				(type default)
			)
			(layer "F.Fab")
		)
		(fp_line
			(start 0.120396 0.3048)
			(end 0.120396 0.2794)
			(stroke
				(width 0.1)
				(type default)
			)
			(layer "F.Fab")
		)
		(fp_line
			(start 0.12065 -0.3048)
			(end 0.67945 -0.3048)
			(stroke
				(width 0.1)
				(type default)
			)
			(layer "F.Fab")
		)
		(fp_line
			(start 0.12065 -0.2794)
			(end 0.12065 -0.3048)
			(stroke
				(width 0.1)
				(type default)
			)
			(layer "F.Fab")
		)
		(fp_line
			(start 0.67945 -0.3048)
			(end 0.67945 0.3048)
			(stroke
				(width 0.1)
				(type default)
			)
			(layer "F.Fab")
		)
		(fp_line
			(start 0.67945 0.3048)
			(end 0.120396 0.3048)
			(stroke
				(width 0.1)
				(type default)
			)
			(layer "F.Fab")
		)
		(pad "1" smd circle
			(at -0.40005 0)
			(size 0 0)
			(layers "F.Cu" "F.Mask" "F.Paste")
			(net "P1V8_AUX")
		)
		(pad "2" smd circle
			(at 0.40005 0)
			(size 0 0)
			(layers "F.Cu" "F.Mask" "F.Paste")
			(net "SMB_M2_P1_1V8AUX_SCL_R")
		)
	)
	(footprint ""
		(layer "F.Cu")
		(at 146.571208 -50.160174)
		(property "Reference" "R1347"
			(at 0 0 0)
			(layer "F.SilkS")
			(hide yes)
			(effects
				(font
					(size 1.27 1.27)
				)
			)
		)
		(property "Value" ""
			(at 0 0 0)
			(layer "F.Fab")
			(effects
				(font
					(size 1.27 1.27)
				)
			)
		)
		(duplicate_pad_numbers_are_jumpers no)
		(fp_line
			(start -0.7874 -0.4064)
			(end 0.7874 -0.4064)
			(stroke
				(width 0.1524)
				(type default)
			)
			(layer "F.SilkS")
		)
		(fp_line
			(start -0.7874 0.4064)
			(end -0.7874 -0.4064)
			(stroke
				(width 0.1524)
				(type default)
			)
			(layer "F.SilkS")
		)
		(fp_line
			(start 0.7874 -0.4064)
			(end 0.7874 0.4064)
			(stroke
				(width 0.1524)
				(type default)
			)
			(layer "F.SilkS")
		)
		(fp_line
			(start 0.7874 0.4064)
			(end -0.7874 0.4064)
			(stroke
				(width 0.1524)
				(type default)
			)
			(layer "F.SilkS")
		)
		(fp_line
			(start -0.67945 -0.305054)
			(end -0.12065 -0.305054)
			(stroke
				(width 0.1)
				(type default)
			)
			(layer "F.Fab")
		)
		(fp_line
			(start -0.67945 0.3048)
			(end -0.67945 -0.305054)
			(stroke
				(width 0.1)
				(type default)
			)
			(layer "F.Fab")
		)
		(fp_line
			(start -0.12065 -0.305054)
			(end -0.12065 -0.2794)
			(stroke
				(width 0.1)
				(type default)
			)
			(layer "F.Fab")
		)
		(fp_line
			(start -0.12065 -0.2794)
			(end 0.12065 -0.2794)
			(stroke
				(width 0.1)
				(type default)
			)
			(layer "F.Fab")
		)
		(fp_line
			(start -0.12065 0.2794)
			(end -0.12065 0.3048)
			(stroke
				(width 0.1)
				(type default)
			)
			(layer "F.Fab")
		)
		(fp_line
			(start -0.12065 0.3048)
			(end -0.67945 0.3048)
			(stroke
				(width 0.1)
				(type default)
			)
			(layer "F.Fab")
		)
		(fp_line
			(start 0.120396 0.2794)
			(end -0.12065 0.2794)
			(stroke
				(width 0.1)
				(type default)
			)
			(layer "F.Fab")
		)
		(fp_line
			(start 0.120396 0.3048)
			(end 0.120396 0.2794)
			(stroke
				(width 0.1)
				(type default)
			)
			(layer "F.Fab")
		)
		(fp_line
			(start 0.12065 -0.3048)
			(end 0.67945 -0.3048)
			(stroke
				(width 0.1)
				(type default)
			)
			(layer "F.Fab")
		)
		(fp_line
			(start 0.12065 -0.2794)
			(end 0.12065 -0.3048)
			(stroke
				(width 0.1)
				(type default)
			)
			(layer "F.Fab")
		)
		(fp_line
			(start 0.67945 -0.3048)
			(end 0.67945 0.3048)
			(stroke
				(width 0.1)
				(type default)
			)
			(layer "F.Fab")
		)
		(fp_line
			(start 0.67945 0.3048)
			(end 0.120396 0.3048)
			(stroke
				(width 0.1)
				(type default)
			)
			(layer "F.Fab")
		)
		(pad "1" smd circle
			(at -0.40005 0)
			(size 0 0)
			(layers "F.Cu" "F.Mask" "F.Paste")
			(net "SMB_INA230_3V3AUX_SDA")
		)
		(pad "2" smd circle
			(at 0.40005 0)
			(size 0 0)
			(layers "F.Cu" "F.Mask" "F.Paste")
			(net "SMB_INA230_7_3V3AUX_SDA_R")
		)
	)
	(footprint ""
		(layer "F.Cu")
		(at 39.309294 -422.06037 180)
		(property "Reference" "R6152"
			(at 0 0 180)
			(layer "F.SilkS")
			(hide yes)
			(effects
				(font
					(size 1.27 1.27)
				)
			)
		)
		(property "Value" ""
			(at 0 0 180)
			(layer "F.Fab")
			(effects
				(font
					(size 1.27 1.27)
				)
			)
		)
		(duplicate_pad_numbers_are_jumpers no)
		(fp_line
			(start 0.32512 0.175006)
			(end -0.32512 0.175006)
			(stroke
				(width 0.1)
				(type default)
			)
			(layer "F.Fab")
		)
		(fp_line
			(start 0.32512 -0.175006)
			(end 0.32512 0.175006)
			(stroke
				(width 0.1)
				(type default)
			)
			(layer "F.Fab")
		)
		(fp_line
			(start -0.32512 0.175006)
			(end -0.32512 -0.175006)
			(stroke
				(width 0.1)
				(type default)
			)
			(layer "F.Fab")
		)
		(fp_line
			(start -0.32512 -0.175006)
			(end 0.32512 -0.175006)
			(stroke
				(width 0.1)
				(type default)
			)
			(layer "F.Fab")
		)
		(pad "1" smd rect
			(at -0.2667 0 180)
			(size 0.3048 0.381)
			(layers "F.Cu" "F.Mask" "F.Paste")
			(net "P2E_MB_BMC_TX_C_DP<0>")
		)
		(pad "2" smd rect
			(at 0.2667 0)
			(size 0.3048 0.381)
			(layers "F.Cu" "F.Mask" "F.Paste")
			(net "P2E_MB_BMC_TX_C_R1_DP<0>")
		)
	)
	(footprint ""
		(layer "F.Cu")
		(at 157.754066 -408.517344 -90)
		(property "Reference" "C6722"
			(at 0 0 270)
			(layer "F.SilkS")
			(hide yes)
			(effects
				(font
					(size 1.27 1.27)
				)
			)
		)
		(property "Value" ""
			(at 0 0 270)
			(layer "F.Fab")
			(effects
				(font
					(size 1.27 1.27)
				)
			)
		)
		(duplicate_pad_numbers_are_jumpers no)
		(fp_line
			(start -0.299974 0.150114)
			(end -0.299974 -0.150114)
			(stroke
				(width 0.1)
				(type default)
			)
			(layer "F.Fab")
		)
		(fp_line
			(start 0.299974 0.150114)
			(end -0.299974 0.150114)
			(stroke
				(width 0.1)
				(type default)
			)
			(layer "F.Fab")
		)
		(fp_line
			(start -0.299974 -0.150114)
			(end 0.299974 -0.150114)
			(stroke
				(width 0.1)
				(type default)
			)
			(layer "F.Fab")
		)
		(fp_line
			(start 0.299974 -0.150114)
			(end 0.299974 0.150114)
			(stroke
				(width 0.1)
				(type default)
			)
			(layer "F.Fab")
		)
		(pad "1" smd rect
			(at -0.2667 0 270)
			(size 0.3048 0.381)
			(layers "F.Cu" "F.Mask" "F.Paste")
			(net "P5E_CPU1_P2_TX_BUF_C_DN<14>")
		)
		(pad "2" smd rect
			(at 0.2667 0 270)
			(size 0.3048 0.381)
			(layers "F.Cu" "F.Mask" "F.Paste")
			(net "P5E_CPU1_P2_TX_BUF_DN<14>")
		)
	)
	(footprint ""
		(layer "F.Cu")
		(at 298.527724 -396.146274)
		(property "Reference" "R595"
			(at 0 0 0)
			(layer "F.SilkS")
			(hide yes)
			(effects
				(font
					(size 1.27 1.27)
				)
			)
		)
		(property "Value" ""
			(at 0 0 0)
			(layer "F.Fab")
			(effects
				(font
					(size 1.27 1.27)
				)
			)
		)
		(duplicate_pad_numbers_are_jumpers no)
		(fp_line
			(start -0.32512 -0.175006)
			(end 0.32512 -0.175006)
			(stroke
				(width 0.1)
				(type default)
			)
			(layer "F.Fab")
		)
		(fp_line
			(start -0.32512 0.175006)
			(end -0.32512 -0.175006)
			(stroke
				(width 0.1)
				(type default)
			)
			(layer "F.Fab")
		)
		(fp_line
			(start 0.32512 -0.175006)
			(end 0.32512 0.175006)
			(stroke
				(width 0.1)
				(type default)
			)
			(layer "F.Fab")
		)
		(fp_line
			(start 0.32512 0.175006)
			(end -0.32512 0.175006)
			(stroke
				(width 0.1)
				(type default)
			)
			(layer "F.Fab")
		)
		(pad "1" smd rect
			(at -0.2667 0)
			(size 0.3048 0.381)
			(layers "F.Cu" "F.Mask" "F.Paste")
			(net "CLK_100M_RETIMER_CPU0_P0_R_DP")
		)
		(pad "2" smd rect
			(at 0.2667 0 180)
			(size 0.3048 0.381)
			(layers "F.Cu" "F.Mask" "F.Paste")
			(net "CLK_100M_RETIMER_CPU0_P0_DP")
		)
	)
)
